(kicad_pcb
	(version 20260206)
	(generator "pcbnew")
	(generator_version "10.0")
	(general
		(thickness 1.6)
		(legacy_teardrops no)
	)
	(paper "A4")
	(title_block
		(title "Bryce Canyon_F.DPB_16315-1-OCP.brd")
		(comment 1 "Bryce Canyon / footprints 654-659 of 2223")
	)
	(layers
		(0 "F.Cu" signal "TOP")
		(4 "In1.Cu" signal "L2GND")
		(6 "In2.Cu" signal "L3")
		(8 "In3.Cu" signal "L4GND")
		(10 "In4.Cu" signal "L5")
		(12 "In5.Cu" signal "L6VCC")
		(14 "In6.Cu" signal "L7VCC")
		(16 "In7.Cu" signal "L8")
		(18 "In8.Cu" signal "L9GND")
		(20 "In9.Cu" signal "L10")
		(22 "In10.Cu" signal "L11GND")
		(2 "B.Cu" signal "BOTTOM")
		(9 "F.Adhes" user "F.Adhesive")
		(11 "B.Adhes" user "B.Adhesive")
		(13 "F.Paste" user "Package Geometry/Pastemask Top")
		(15 "B.Paste" user "Package Geometry/Pastemask Bottom")
		(5 "F.SilkS" user "Ref Des/Silkscreen Top")
		(7 "B.SilkS" user "Ref Des/Silkscreen Bottom")
		(1 "F.Mask" user "Board Geometry/Soldermask Top")
		(3 "B.Mask" user "Board Geometry/Soldermask Bottom")
		(17 "Dwgs.User" user "User.Drawings")
		(19 "Cmts.User" user "User.Comments")
		(21 "Eco1.User" user "User.Eco1")
		(23 "Eco2.User" user "User.Eco2")
		(25 "Edge.Cuts" user "Board Geometry/Outline")
		(27 "Margin" user)
		(31 "F.CrtYd" user "Package Geometry/Place Bound Top")
		(29 "B.CrtYd" user "Package Geometry/Place Bound Bottom")
		(35 "F.Fab" user "Ref Des/Assembly Top")
		(33 "B.Fab" user "Ref Des/Assembly Bottom")
	)
	(footprint ""
		(layer "F.Cu")
		(at 432.724052 -164.443918 90)
		(property "Reference" "R629"
			(at 0 0 90)
			(layer "F.SilkS")
			(hide yes)
			(effects
				(font
					(size 1.27 1.27)
				)
			)
		)
		(property "Value" "200KR2F-L-GP"
			(at 0.064008 -3.993896 90)
			(unlocked yes)
			(layer "F.Fab")
			(hide yes)
			(effects
				(font
					(size 1.016 1.016)
					(thickness 0.1524)
				)
			)
		)
		(property "Device Type" "R402H16"
			(at 0.064008 -5.517896 90)
			(unlocked yes)
			(layer "F.Fab")
			(hide yes)
			(effects
				(font
					(size 1.016 1.016)
					(thickness 0.1524)
				)
			)
		)
		(duplicate_pad_numbers_are_jumpers no)
		(fp_line
			(start 0.508 -0.9398)
			(end -0.508 -0.9398)
			(stroke
				(width 0.1524)
				(type default)
			)
			(layer "F.SilkS")
		)
		(fp_line
			(start -0.508 -0.9398)
			(end -0.508 0.9398)
			(stroke
				(width 0.1524)
				(type default)
			)
			(layer "F.SilkS")
		)
		(fp_rect
			(start -0.508 0.9398)
			(end 0.508 -0.9398)
			(stroke
				(width 0)
				(type default)
			)
			(fill no)
			(layer "F.CrtYd")
		)
		(fp_rect
			(start -0.508 0.9398)
			(end 0.508 -0.9398)
			(stroke
				(width 0)
				(type default)
			)
			(fill no)
			(layer "F.Fab")
		)
		(pad "1" smd custom
			(at 0 -0.4445 90)
			(size 0.1397 0.1397)
			(layers "F.Cu" "F.Mask" "F.Paste")
			(net "SW_HDD_R21")
			(options
				(clearance outline)
				(anchor circle)
			)
			(primitives
				(gr_poly
					(pts
						(arc
							(start -0.1778 -0.2794)
							(mid -0.249642 -0.249642)
							(end -0.2794 -0.1778)
						)
						(arc
							(start -0.2794 0.1778)
							(mid -0.249642 0.249642)
							(end -0.1778 0.2794)
						)
						(arc
							(start 0.1778 0.2794)
							(mid 0.249642 0.249642)
							(end 0.2794 0.1778)
						)
						(arc
							(start 0.2794 -0.1778)
							(mid 0.249642 -0.249642)
							(end 0.1778 -0.2794)
						)
					)
					(width 0)
					(fill yes)
				)
			)
		)
		(pad "2" smd custom
			(at 0 0.4445 90)
			(size 0.1397 0.1397)
			(layers "F.Cu" "F.Mask" "F.Paste")
			(net "SW_HDD_N21")
			(options
				(clearance outline)
				(anchor circle)
			)
			(primitives
				(gr_poly
					(pts
						(arc
							(start -0.1778 -0.2794)
							(mid -0.249642 -0.249642)
							(end -0.2794 -0.1778)
						)
						(arc
							(start -0.2794 0.1778)
							(mid -0.249642 0.249642)
							(end -0.1778 0.2794)
						)
						(arc
							(start 0.1778 0.2794)
							(mid 0.249642 0.249642)
							(end 0.2794 0.1778)
						)
						(arc
							(start 0.2794 -0.1778)
							(mid 0.249642 -0.249642)
							(end 0.1778 -0.2794)
						)
					)
					(width 0)
					(fill yes)
				)
			)
		)
	)
	(footprint ""
		(layer "F.Cu")
		(at 215.799416 -390.80186 90)
		(property "Reference" "C688"
			(at 0 0 90)
			(layer "F.SilkS")
			(hide yes)
			(effects
				(font
					(size 1.27 1.27)
				)
			)
		)
		(property "Value" "SCD1U16V2KX-3GP"
			(at 1.1811 -2.7051 90)
			(unlocked yes)
			(layer "F.Fab")
			(hide yes)
			(effects
				(font
					(size 1.016 1.016)
					(thickness 0.1524)
				)
			)
		)
		(property "Device Type" "C402H22"
			(at 1.1811 -4.2291 90)
			(unlocked yes)
			(layer "F.Fab")
			(hide yes)
			(effects
				(font
					(size 1.016 1.016)
					(thickness 0.1524)
				)
			)
		)
		(duplicate_pad_numbers_are_jumpers no)
		(fp_rect
			(start -0.4318 0.9525)
			(end 0.4318 -0.9525)
			(stroke
				(width 0)
				(type default)
			)
			(fill no)
			(layer "F.CrtYd")
		)
		(fp_rect
			(start -0.4318 0.9525)
			(end 0.4318 -0.9525)
			(stroke
				(width 0)
				(type default)
			)
			(fill no)
			(layer "F.Fab")
		)
		(pad "1" smd custom
			(at 0 -0.4445 90)
			(size 0.1524 0.1524)
			(layers "F.Cu" "F.Mask" "F.Paste")
			(net "P3V3_STBY_B")
			(options
				(clearance outline)
				(anchor circle)
			)
			(primitives
				(gr_poly
					(pts
						(arc
							(start 0.3048 -0.2032)
							(mid 0.275042 -0.275042)
							(end 0.2032 -0.3048)
						)
						(arc
							(start -0.2032 -0.3048)
							(mid -0.275042 -0.275042)
							(end -0.3048 -0.2032)
						)
						(arc
							(start -0.3048 0.2032)
							(mid -0.275042 0.275042)
							(end -0.2032 0.3048)
						)
						(arc
							(start 0.2032 0.3048)
							(mid 0.275042 0.275042)
							(end 0.3048 0.2032)
						)
					)
					(width 0)
					(fill yes)
				)
			)
		)
		(pad "2" smd custom
			(at 0 0.4445 90)
			(size 0.1524 0.1524)
			(layers "F.Cu" "F.Mask" "F.Paste")
			(net "GND")
			(options
				(clearance outline)
				(anchor circle)
			)
			(primitives
				(gr_poly
					(pts
						(arc
							(start 0.3048 -0.2032)
							(mid 0.275042 -0.275042)
							(end 0.2032 -0.3048)
						)
						(arc
							(start -0.2032 -0.3048)
							(mid -0.275042 -0.275042)
							(end -0.3048 -0.2032)
						)
						(arc
							(start -0.3048 0.2032)
							(mid -0.275042 0.275042)
							(end -0.2032 0.3048)
						)
						(arc
							(start 0.2032 0.3048)
							(mid 0.275042 0.275042)
							(end 0.3048 0.2032)
						)
					)
					(width 0)
					(fill yes)
				)
			)
		)
	)
	(footprint ""
		(layer "F.Cu")
		(at 429.549052 -167.872918 -90)
		(property "Reference" "Q125"
			(at 0 0 270)
			(layer "F.SilkS")
			(hide yes)
			(effects
				(font
					(size 1.27 1.27)
				)
			)
		)
		(property "Value" "AO4406AL-GP"
			(at -3.707384 -1.5367 270)
			(unlocked yes)
			(layer "F.Fab")
			(hide yes)
			(effects
				(font
					(size 1.016 1.016)
					(thickness 0.1524)
				)
			)
		)
		(property "Device Type" "SOIC8H69"
			(at -3.707384 -3.0607 270)
			(unlocked yes)
			(layer "F.Fab")
			(hide yes)
			(effects
				(font
					(size 1.016 1.016)
					(thickness 0.1524)
				)
			)
		)
		(duplicate_pad_numbers_are_jumpers no)
		(fp_line
			(start -2.6289 3.4417)
			(end -2.6289 1.4732)
			(stroke
				(width 0.381)
				(type default)
			)
			(layer "F.SilkS")
		)
		(fp_line
			(start -2.7432 1.4224)
			(end -2.6416 1.4224)
			(stroke
				(width 0.1524)
				(type default)
			)
			(layer "F.SilkS")
		)
		(fp_line
			(start -2.7432 1.4224)
			(end 2.1336 1.4224)
			(stroke
				(width 0.1524)
				(type default)
			)
			(layer "F.SilkS")
		)
		(fp_line
			(start 2.1336 1.4224)
			(end 2.1336 -1.4224)
			(stroke
				(width 0.1524)
				(type default)
			)
			(layer "F.SilkS")
		)
		(fp_line
			(start -2.1844 -0.0508)
			(end -2.7178 0.508)
			(stroke
				(width 0.1524)
				(type default)
			)
			(layer "F.SilkS")
		)
		(fp_line
			(start -2.7178 -0.508)
			(end -2.1844 -0.0508)
			(stroke
				(width 0.1524)
				(type default)
			)
			(layer "F.SilkS")
		)
		(fp_line
			(start -2.7432 -1.4224)
			(end -2.7432 1.4224)
			(stroke
				(width 0.1524)
				(type default)
			)
			(layer "F.SilkS")
		)
		(fp_line
			(start 2.1336 -1.4224)
			(end -2.7432 -1.4224)
			(stroke
				(width 0.1524)
				(type default)
			)
			(layer "F.SilkS")
		)
		(fp_poly
			(pts
				(xy -2.2098 -1.4224) (xy -2.2098 1.4224) (xy 2.2098 1.4224) (xy 2.2098 -1.4224)
			)
			(stroke
				(width 0)
				(type default)
			)
			(fill yes)
			(layer "F.SilkS")
		)
		(fp_rect
			(start -2.450084 2.999994)
			(end 2.450084 -2.999994)
			(stroke
				(width 0)
				(type default)
			)
			(fill no)
			(layer "F.CrtYd")
		)
		(fp_poly
			(pts
				(xy -2.8194 3.6322) (xy -2.8194 -3.6322) (xy 2.8194 -3.6322) (xy 2.8194 1.18364) (xy 2.450084 1.18364)
				(xy 2.450084 -2.999994) (xy -2.450084 -2.999994) (xy -2.450084 2.999994) (xy 2.450084 2.999994)
				(xy 2.450084 1.18618) (xy 2.8194 1.18618) (xy 2.8194 3.6322)
			)
			(stroke
				(width 0)
				(type default)
			)
			(fill no)
			(layer "F.CrtYd")
		)
		(fp_rect
			(start -2.8194 3.6322)
			(end 2.8194 -3.6322)
			(stroke
				(width 0)
				(type default)
			)
			(fill no)
			(layer "F.Fab")
		)
		(pad "1" smd rect
			(at -1.905 2.54 270)
			(size 0.635 1.651)
			(layers "F.Cu" "F.Mask" "F.Paste")
			(net "P5V_HDD21")
		)
		(pad "2" smd rect
			(at -0.635 2.54 270)
			(size 0.635 1.651)
			(layers "F.Cu" "F.Mask" "F.Paste")
			(net "P5V_HDD21")
		)
		(pad "3" smd rect
			(at 0.635 2.54 270)
			(size 0.635 1.651)
			(layers "F.Cu" "F.Mask" "F.Paste")
			(net "P5V_HDD21")
		)
		(pad "4" smd rect
			(at 1.905 2.54 270)
			(size 0.635 1.651)
			(layers "F.Cu" "F.Mask" "F.Paste")
			(net "SW_HDD_P21")
		)
		(pad "5" smd rect
			(at 1.905 -2.54 270)
			(size 0.635 1.651)
			(layers "F.Cu" "F.Mask" "F.Paste")
			(net "P5V_A_4")
		)
		(pad "6" smd rect
			(at 0.635 -2.54 270)
			(size 0.635 1.651)
			(layers "F.Cu" "F.Mask" "F.Paste")
			(net "P5V_A_4")
		)
		(pad "7" smd rect
			(at -0.635 -2.54 270)
			(size 0.635 1.651)
			(layers "F.Cu" "F.Mask" "F.Paste")
			(net "P5V_A_4")
		)
		(pad "8" smd rect
			(at -1.905 -2.54 270)
			(size 0.635 1.651)
			(layers "F.Cu" "F.Mask" "F.Paste")
			(net "P5V_A_4")
		)
	)
	(footprint ""
		(layer "F.Cu")
		(at 459.4479 -157.585918 180)
		(property "Reference" "R644"
			(at 0 0 180)
			(layer "F.SilkS")
			(hide yes)
			(effects
				(font
					(size 1.27 1.27)
				)
			)
		)
		(property "Value" "1KR2F-3-GP"
			(at 0.064008 -3.993896 180)
			(unlocked yes)
			(layer "F.Fab")
			(hide yes)
			(effects
				(font
					(size 1.016 1.016)
					(thickness 0.1524)
				)
			)
		)
		(property "Device Type" "R402H16"
			(at 0.064008 -5.517896 180)
			(unlocked yes)
			(layer "F.Fab")
			(hide yes)
			(effects
				(font
					(size 1.016 1.016)
					(thickness 0.1524)
				)
			)
		)
		(duplicate_pad_numbers_are_jumpers no)
		(fp_line
			(start 0.508 -0.9398)
			(end -0.508 -0.9398)
			(stroke
				(width 0.1524)
				(type default)
			)
			(layer "F.SilkS")
		)
		(fp_line
			(start -0.508 -0.9398)
			(end -0.508 0.9398)
			(stroke
				(width 0.1524)
				(type default)
			)
			(layer "F.SilkS")
		)
		(fp_rect
			(start -0.508 0.9398)
			(end 0.508 -0.9398)
			(stroke
				(width 0)
				(type default)
			)
			(fill no)
			(layer "F.CrtYd")
		)
		(fp_rect
			(start -0.508 0.9398)
			(end 0.508 -0.9398)
			(stroke
				(width 0)
				(type default)
			)
			(fill no)
			(layer "F.Fab")
		)
		(pad "1" smd custom
			(at 0 -0.4445 180)
			(size 0.1397 0.1397)
			(layers "F.Cu" "F.Mask" "F.Paste")
			(net "P3V3_STBY_A")
			(options
				(clearance outline)
				(anchor circle)
			)
			(primitives
				(gr_poly
					(pts
						(arc
							(start -0.1778 -0.2794)
							(mid -0.249642 -0.249642)
							(end -0.2794 -0.1778)
						)
						(arc
							(start -0.2794 0.1778)
							(mid -0.249642 0.249642)
							(end -0.1778 0.2794)
						)
						(arc
							(start 0.1778 0.2794)
							(mid 0.249642 0.249642)
							(end 0.2794 0.1778)
						)
						(arc
							(start 0.2794 -0.1778)
							(mid 0.249642 -0.249642)
							(end 0.1778 -0.2794)
						)
					)
					(width 0)
					(fill yes)
				)
			)
		)
		(pad "2" smd custom
			(at 0 0.4445 180)
			(size 0.1397 0.1397)
			(layers "F.Cu" "F.Mask" "F.Paste")
			(net "SW_PWR_R_HDD22")
			(options
				(clearance outline)
				(anchor circle)
			)
			(primitives
				(gr_poly
					(pts
						(arc
							(start -0.1778 -0.2794)
							(mid -0.249642 -0.249642)
							(end -0.2794 -0.1778)
						)
						(arc
							(start -0.2794 0.1778)
							(mid -0.249642 0.249642)
							(end -0.1778 0.2794)
						)
						(arc
							(start 0.1778 0.2794)
							(mid 0.249642 0.249642)
							(end 0.2794 0.1778)
						)
						(arc
							(start 0.2794 -0.1778)
							(mid 0.249642 -0.249642)
							(end 0.1778 -0.2794)
						)
					)
					(width 0)
					(fill yes)
				)
			)
		)
	)
	(footprint ""
		(layer "F.Cu")
		(at 438.293764 -127.724408 180)
		(property "Reference" "Q249"
			(at 0 0 180)
			(layer "F.SilkS")
			(hide yes)
			(effects
				(font
					(size 1.27 1.27)
				)
			)
		)
		(property "Value" "2N7002K-2-GP"
			(at 0.127 -8.9662 180)
			(unlocked yes)
			(layer "F.Fab")
			(hide yes)
			(effects
				(font
					(size 1.016 1.016)
					(thickness 0.1524)
				)
			)
		)
		(property "Device Type" "SOT23DGS2D4H44"
			(at 0.127 -10.4902 180)
			(unlocked yes)
			(layer "F.Fab")
			(hide yes)
			(effects
				(font
					(size 1.016 1.016)
					(thickness 0.1524)
				)
			)
		)
		(duplicate_pad_numbers_are_jumpers no)
		(fp_line
			(start 1.651 1.778)
			(end 1.651 -1.778)
			(stroke
				(width 0.1524)
				(type default)
			)
			(layer "F.SilkS")
		)
		(fp_line
			(start 1.651 -1.778)
			(end -1.651 -1.778)
			(stroke
				(width 0.1524)
				(type default)
			)
			(layer "F.SilkS")
		)
		(fp_line
			(start -1.651 1.778)
			(end 1.651 1.778)
			(stroke
				(width 0.1524)
				(type default)
			)
			(layer "F.SilkS")
		)
		(fp_line
			(start -1.651 -1.778)
			(end -1.651 1.778)
			(stroke
				(width 0.1524)
				(type default)
			)
			(layer "F.SilkS")
		)
		(fp_poly
			(pts
				(xy -1.778 1.8796) (xy -1.778 -1.8796) (xy 1.778 -1.8796) (xy 1.778 1.8796)
			)
			(stroke
				(width 0)
				(type default)
			)
			(fill no)
			(layer "F.CrtYd")
		)
		(fp_poly
			(pts
				(xy -1.778 1.8796) (xy -1.778 -1.8796) (xy 1.778 -1.8796) (xy 1.778 1.8796)
			)
			(stroke
				(width 0)
				(type default)
			)
			(fill no)
			(layer "F.Fab")
		)
		(pad "D" smd custom
			(at 0 -0.9525 180)
			(size 0.1905 0.1905)
			(layers "F.Cu" "F.Mask" "F.Paste")
			(net "FLT_HDD22_N")
			(options
				(clearance outline)
				(anchor circle)
			)
			(primitives
				(gr_poly
					(pts
						(arc
							(start -0.1778 0.5715)
							(mid -0.321484 0.511984)
							(end -0.381 0.3683)
						)
						(arc
							(start -0.381 -0.3683)
							(mid -0.321484 -0.511984)
							(end -0.1778 -0.5715)
						)
						(arc
							(start 0.1778 -0.5715)
							(mid 0.321484 -0.511984)
							(end 0.381 -0.3683)
						)
						(arc
							(start 0.381 0.3683)
							(mid 0.321484 0.511984)
							(end 0.1778 0.5715)
						)
					)
					(width 0)
					(fill yes)
				)
			)
		)
		(pad "G" smd custom
			(at -0.98425 0.9525 180)
			(size 0.1905 0.1905)
			(layers "F.Cu" "F.Mask" "F.Paste")
			(net "DRIVE_A_22_FLT_LED")
			(options
				(clearance outline)
				(anchor circle)
			)
			(primitives
				(gr_poly
					(pts
						(arc
							(start -0.1778 0.5715)
							(mid -0.321484 0.511984)
							(end -0.381 0.3683)
						)
						(arc
							(start -0.381 -0.3683)
							(mid -0.321484 -0.511984)
							(end -0.1778 -0.5715)
						)
						(arc
							(start 0.1778 -0.5715)
							(mid 0.321484 -0.511984)
							(end 0.381 -0.3683)
						)
						(arc
							(start 0.381 0.3683)
							(mid 0.321484 0.511984)
							(end 0.1778 0.5715)
						)
					)
					(width 0)
					(fill yes)
				)
			)
		)
		(pad "S" smd custom
			(at 0.98425 0.9525 180)
			(size 0.1905 0.1905)
			(layers "F.Cu" "F.Mask" "F.Paste")
			(net "GND")
			(options
				(clearance outline)
				(anchor circle)
			)
			(primitives
				(gr_poly
					(pts
						(arc
							(start -0.1778 0.5715)
							(mid -0.321484 0.511984)
							(end -0.381 0.3683)
						)
						(arc
							(start -0.381 -0.3683)
							(mid -0.321484 -0.511984)
							(end -0.1778 -0.5715)
						)
						(arc
							(start 0.1778 -0.5715)
							(mid 0.321484 -0.511984)
							(end 0.381 -0.3683)
						)
						(arc
							(start 0.381 0.3683)
							(mid 0.321484 0.511984)
							(end 0.1778 0.5715)
						)
					)
					(width 0)
					(fill yes)
				)
			)
		)
	)
	(footprint ""
		(layer "F.Cu")
		(at 256.843276 -248.87936)
		(property "Reference" "R55"
			(at 0 0 0)
			(layer "F.SilkS")
			(hide yes)
			(effects
				(font
					(size 1.27 1.27)
				)
			)
		)
		(property "Value" "4K7R2F-GP"
			(at 0.064008 -3.993896 0)
			(unlocked yes)
			(layer "F.Fab")
			(hide yes)
			(effects
				(font
					(size 1.016 1.016)
					(thickness 0.1524)
				)
			)
		)
		(property "Device Type" "R402H16"
			(at 0.064008 -5.517896 0)
			(unlocked yes)
			(layer "F.Fab")
			(hide yes)
			(effects
				(font
					(size 1.016 1.016)
					(thickness 0.1524)
				)
			)
		)
		(duplicate_pad_numbers_are_jumpers no)
		(fp_line
			(start -0.508 -0.9398)
			(end -0.508 0.9398)
			(stroke
				(width 0.1524)
				(type default)
			)
			(layer "F.SilkS")
		)
		(fp_line
			(start 0.508 -0.9398)
			(end -0.508 -0.9398)
			(stroke
				(width 0.1524)
				(type default)
			)
			(layer "F.SilkS")
		)
		(fp_rect
			(start -0.508 0.9398)
			(end 0.508 -0.9398)
			(stroke
				(width 0)
				(type default)
			)
			(fill no)
			(layer "F.CrtYd")
		)
		(fp_rect
			(start -0.508 0.9398)
			(end 0.508 -0.9398)
			(stroke
				(width 0)
				(type default)
			)
			(fill no)
			(layer "F.Fab")
		)
		(pad "1" smd custom
			(at 0 -0.4445)
			(size 0.1397 0.1397)
			(layers "F.Cu" "F.Mask" "F.Paste")
			(net "IO_EXP6_A2")
			(options
				(clearance outline)
				(anchor circle)
			)
			(primitives
				(gr_poly
					(pts
						(arc
							(start -0.1778 -0.2794)
							(mid -0.249642 -0.249642)
							(end -0.2794 -0.1778)
						)
						(arc
							(start -0.2794 0.1778)
							(mid -0.249642 0.249642)
							(end -0.1778 0.2794)
						)
						(arc
							(start 0.1778 0.2794)
							(mid 0.249642 0.249642)
							(end 0.2794 0.1778)
						)
						(arc
							(start 0.2794 -0.1778)
							(mid 0.249642 -0.249642)
							(end 0.1778 -0.2794)
						)
					)
					(width 0)
					(fill yes)
				)
			)
		)
		(pad "2" smd custom
			(at 0 0.4445)
			(size 0.1397 0.1397)
			(layers "F.Cu" "F.Mask" "F.Paste")
			(net "GND")
			(options
				(clearance outline)
				(anchor circle)
			)
			(primitives
				(gr_poly
					(pts
						(arc
							(start -0.1778 -0.2794)
							(mid -0.249642 -0.249642)
							(end -0.2794 -0.1778)
						)
						(arc
							(start -0.2794 0.1778)
							(mid -0.249642 0.249642)
							(end -0.1778 0.2794)
						)
						(arc
							(start 0.1778 0.2794)
							(mid 0.249642 0.249642)
							(end 0.2794 0.1778)
						)
						(arc
							(start 0.2794 -0.1778)
							(mid 0.249642 -0.249642)
							(end 0.1778 -0.2794)
						)
					)
					(width 0)
					(fill yes)
				)
			)
		)
	)
)
